(kicad_pcb
	(version 20260206)
	(generator "pcbnew")
	(generator_version "10.0")
	(general
		(thickness 1.6)
		(legacy_teardrops no)
	)
	(paper "A4")
	(title_block
		(title "03242023_DA0F0TMBIJ0_F0T_Motherboard_J_brd_V01_OCP.brd")
		(comment 1 "Grand Teton / footprints 1-7 of 6105")
	)
	(layers
		(0 "F.Cu" signal "TOP")
		(4 "In1.Cu" signal "GND")
		(6 "In2.Cu" signal "IN1")
		(8 "In3.Cu" signal "GND1")
		(10 "In4.Cu" signal "IN2")
		(12 "In5.Cu" signal "GND2")
		(14 "In6.Cu" signal "IN3")
		(16 "In7.Cu" signal "GND3")
		(18 "In8.Cu" signal "VCC")
		(20 "In9.Cu" signal "VCC1")
		(22 "In10.Cu" signal "GND4")
		(24 "In11.Cu" signal "IN4")
		(26 "In12.Cu" signal "GND5")
		(28 "In13.Cu" signal "IN5")
		(30 "In14.Cu" signal "GND6")
		(32 "In15.Cu" signal "IN6")
		(34 "In16.Cu" signal "GND7")
		(2 "B.Cu" signal "BOTTOM")
		(9 "F.Adhes" user "F.Adhesive")
		(11 "B.Adhes" user "B.Adhesive")
		(13 "F.Paste" user "Package Geometry/Pastemask Top")
		(15 "B.Paste" user "Package Geometry/Pastemask Bottom")
		(5 "F.SilkS" user "Ref Des/Silkscreen Top")
		(7 "B.SilkS" user "Ref Des/Silkscreen Bottom")
		(1 "F.Mask" user "Board Geometry/Soldermask Top")
		(3 "B.Mask" user "Board Geometry/Soldermask Bottom")
		(17 "Dwgs.User" user "User.Drawings")
		(19 "Cmts.User" user "User.Comments")
		(21 "Eco1.User" user "User.Eco1")
		(23 "Eco2.User" user "User.Eco2")
		(25 "Edge.Cuts" user "Board Geometry/Outline")
		(27 "Margin" user)
		(31 "F.CrtYd" user "Package Geometry/Place Bound Top")
		(29 "B.CrtYd" user "Package Geometry/Place Bound Bottom")
		(35 "F.Fab" user "Ref Des/Assembly Top")
		(33 "B.Fab" user "Ref Des/Assembly Bottom")
	)
	(footprint ""
		(layer "F.Cu")
		(at 72.26681 -74.901552 -90)
		(property "Reference" "R3095"
			(at 0 0 270)
			(layer "F.SilkS")
			(hide yes)
			(effects
				(font
					(size 1.27 1.27)
				)
			)
		)
		(property "Value" ""
			(at 0 0 270)
			(layer "F.Fab")
			(effects
				(font
					(size 1.27 1.27)
				)
			)
		)
		(duplicate_pad_numbers_are_jumpers no)
		(fp_line
			(start -0.7874 0.4064)
			(end -0.7874 -0.4064)
			(stroke
				(width 0.1524)
				(type default)
			)
			(layer "F.SilkS")
		)
		(fp_line
			(start 0.7874 0.4064)
			(end -0.7874 0.4064)
			(stroke
				(width 0.1524)
				(type default)
			)
			(layer "F.SilkS")
		)
		(fp_line
			(start -0.7874 -0.4064)
			(end 0.7874 -0.4064)
			(stroke
				(width 0.1524)
				(type default)
			)
			(layer "F.SilkS")
		)
		(fp_line
			(start 0.7874 -0.4064)
			(end 0.7874 0.4064)
			(stroke
				(width 0.1524)
				(type default)
			)
			(layer "F.SilkS")
		)
		(fp_line
			(start -0.67945 0.3048)
			(end -0.67945 -0.305054)
			(stroke
				(width 0.1)
				(type default)
			)
			(layer "F.Fab")
		)
		(fp_line
			(start -0.12065 0.3048)
			(end -0.67945 0.3048)
			(stroke
				(width 0.1)
				(type default)
			)
			(layer "F.Fab")
		)
		(fp_line
			(start 0.120396 0.3048)
			(end 0.120396 0.2794)
			(stroke
				(width 0.1)
				(type default)
			)
			(layer "F.Fab")
		)
		(fp_line
			(start 0.67945 0.3048)
			(end 0.120396 0.3048)
			(stroke
				(width 0.1)
				(type default)
			)
			(layer "F.Fab")
		)
		(fp_line
			(start -0.12065 0.2794)
			(end -0.12065 0.3048)
			(stroke
				(width 0.1)
				(type default)
			)
			(layer "F.Fab")
		)
		(fp_line
			(start 0.120396 0.2794)
			(end -0.12065 0.2794)
			(stroke
				(width 0.1)
				(type default)
			)
			(layer "F.Fab")
		)
		(fp_line
			(start -0.12065 -0.2794)
			(end 0.12065 -0.2794)
			(stroke
				(width 0.1)
				(type default)
			)
			(layer "F.Fab")
		)
		(fp_line
			(start 0.12065 -0.2794)
			(end 0.12065 -0.3048)
			(stroke
				(width 0.1)
				(type default)
			)
			(layer "F.Fab")
		)
		(fp_line
			(start 0.12065 -0.3048)
			(end 0.67945 -0.3048)
			(stroke
				(width 0.1)
				(type default)
			)
			(layer "F.Fab")
		)
		(fp_line
			(start 0.67945 -0.3048)
			(end 0.67945 0.3048)
			(stroke
				(width 0.1)
				(type default)
			)
			(layer "F.Fab")
		)
		(fp_line
			(start -0.67945 -0.305054)
			(end -0.12065 -0.305054)
			(stroke
				(width 0.1)
				(type default)
			)
			(layer "F.Fab")
		)
		(fp_line
			(start -0.12065 -0.305054)
			(end -0.12065 -0.2794)
			(stroke
				(width 0.1)
				(type default)
			)
			(layer "F.Fab")
		)
		(pad "1" smd circle
			(at -0.40005 0 270)
			(size 0 0)
			(layers "F.Cu" "F.Mask" "F.Paste")
			(net "LED_PWRGD_PVCCFA_EHV_FIVRA_CPU1")
		)
		(pad "2" smd circle
			(at 0.40005 0 270)
			(size 0 0)
			(layers "F.Cu" "F.Mask" "F.Paste")
			(net "P3V3_AUX")
		)
	)
	(footprint ""
		(layer "F.Cu")
		(at 398.133824 -186.865514)
		(property "Reference" "PR521"
			(at 0 0 0)
			(layer "F.SilkS")
			(hide yes)
			(effects
				(font
					(size 1.27 1.27)
				)
			)
		)
		(property "Value" ""
			(at 0 0 0)
			(layer "F.Fab")
			(effects
				(font
					(size 1.27 1.27)
				)
			)
		)
		(duplicate_pad_numbers_are_jumpers no)
		(fp_line
			(start -0.7874 -0.4064)
			(end 0.7874 -0.4064)
			(stroke
				(width 0.1524)
				(type default)
			)
			(layer "F.SilkS")
		)
		(fp_line
			(start -0.7874 0.4064)
			(end -0.7874 -0.4064)
			(stroke
				(width 0.1524)
				(type default)
			)
			(layer "F.SilkS")
		)
		(fp_line
			(start 0.7874 -0.4064)
			(end 0.7874 0.4064)
			(stroke
				(width 0.1524)
				(type default)
			)
			(layer "F.SilkS")
		)
		(fp_line
			(start 0.7874 0.4064)
			(end -0.7874 0.4064)
			(stroke
				(width 0.1524)
				(type default)
			)
			(layer "F.SilkS")
		)
		(fp_line
			(start -0.67945 -0.305054)
			(end -0.12065 -0.305054)
			(stroke
				(width 0.1)
				(type default)
			)
			(layer "F.Fab")
		)
		(fp_line
			(start -0.67945 0.3048)
			(end -0.67945 -0.305054)
			(stroke
				(width 0.1)
				(type default)
			)
			(layer "F.Fab")
		)
		(fp_line
			(start -0.12065 -0.305054)
			(end -0.12065 -0.2794)
			(stroke
				(width 0.1)
				(type default)
			)
			(layer "F.Fab")
		)
		(fp_line
			(start -0.12065 -0.2794)
			(end 0.12065 -0.2794)
			(stroke
				(width 0.1)
				(type default)
			)
			(layer "F.Fab")
		)
		(fp_line
			(start -0.12065 0.2794)
			(end -0.12065 0.3048)
			(stroke
				(width 0.1)
				(type default)
			)
			(layer "F.Fab")
		)
		(fp_line
			(start -0.12065 0.3048)
			(end -0.67945 0.3048)
			(stroke
				(width 0.1)
				(type default)
			)
			(layer "F.Fab")
		)
		(fp_line
			(start 0.120396 0.2794)
			(end -0.12065 0.2794)
			(stroke
				(width 0.1)
				(type default)
			)
			(layer "F.Fab")
		)
		(fp_line
			(start 0.120396 0.3048)
			(end 0.120396 0.2794)
			(stroke
				(width 0.1)
				(type default)
			)
			(layer "F.Fab")
		)
		(fp_line
			(start 0.12065 -0.3048)
			(end 0.67945 -0.3048)
			(stroke
				(width 0.1)
				(type default)
			)
			(layer "F.Fab")
		)
		(fp_line
			(start 0.12065 -0.2794)
			(end 0.12065 -0.3048)
			(stroke
				(width 0.1)
				(type default)
			)
			(layer "F.Fab")
		)
		(fp_line
			(start 0.67945 -0.3048)
			(end 0.67945 0.3048)
			(stroke
				(width 0.1)
				(type default)
			)
			(layer "F.Fab")
		)
		(fp_line
			(start 0.67945 0.3048)
			(end 0.120396 0.3048)
			(stroke
				(width 0.1)
				(type default)
			)
			(layer "F.Fab")
		)
		(pad "1" smd circle
			(at -0.40005 0)
			(size 0 0)
			(layers "F.Cu" "F.Mask" "F.Paste")
			(net "VSENSE_PVCCINFAON_CPU0_DP")
		)
		(pad "2" smd circle
			(at 0.40005 0)
			(size 0 0)
			(layers "F.Cu" "F.Mask" "F.Paste")
			(net "PVCCINFAON_CPU0")
		)
	)
	(footprint ""
		(layer "F.Cu")
		(at 209.74558 -128.544828 180)
		(property "Reference" "R1693"
			(at 0 0 180)
			(layer "F.SilkS")
			(hide yes)
			(effects
				(font
					(size 1.27 1.27)
				)
			)
		)
		(property "Value" ""
			(at 0 0 180)
			(layer "F.Fab")
			(effects
				(font
					(size 1.27 1.27)
				)
			)
		)
		(duplicate_pad_numbers_are_jumpers no)
		(fp_line
			(start 0.7874 0.4064)
			(end -0.7874 0.4064)
			(stroke
				(width 0.1524)
				(type default)
			)
			(layer "F.SilkS")
		)
		(fp_line
			(start 0.7874 -0.4064)
			(end 0.7874 0.4064)
			(stroke
				(width 0.1524)
				(type default)
			)
			(layer "F.SilkS")
		)
		(fp_line
			(start -0.7874 0.4064)
			(end -0.7874 -0.4064)
			(stroke
				(width 0.1524)
				(type default)
			)
			(layer "F.SilkS")
		)
		(fp_line
			(start -0.7874 -0.4064)
			(end 0.7874 -0.4064)
			(stroke
				(width 0.1524)
				(type default)
			)
			(layer "F.SilkS")
		)
		(fp_line
			(start 0.67945 0.3048)
			(end 0.120396 0.3048)
			(stroke
				(width 0.1)
				(type default)
			)
			(layer "F.Fab")
		)
		(fp_line
			(start 0.67945 -0.3048)
			(end 0.67945 0.3048)
			(stroke
				(width 0.1)
				(type default)
			)
			(layer "F.Fab")
		)
		(fp_line
			(start 0.12065 -0.2794)
			(end 0.12065 -0.3048)
			(stroke
				(width 0.1)
				(type default)
			)
			(layer "F.Fab")
		)
		(fp_line
			(start 0.12065 -0.3048)
			(end 0.67945 -0.3048)
			(stroke
				(width 0.1)
				(type default)
			)
			(layer "F.Fab")
		)
		(fp_line
			(start 0.120396 0.3048)
			(end 0.120396 0.2794)
			(stroke
				(width 0.1)
				(type default)
			)
			(layer "F.Fab")
		)
		(fp_line
			(start 0.120396 0.2794)
			(end -0.12065 0.2794)
			(stroke
				(width 0.1)
				(type default)
			)
			(layer "F.Fab")
		)
		(fp_line
			(start -0.12065 0.3048)
			(end -0.67945 0.3048)
			(stroke
				(width 0.1)
				(type default)
			)
			(layer "F.Fab")
		)
		(fp_line
			(start -0.12065 0.2794)
			(end -0.12065 0.3048)
			(stroke
				(width 0.1)
				(type default)
			)
			(layer "F.Fab")
		)
		(fp_line
			(start -0.12065 -0.2794)
			(end 0.12065 -0.2794)
			(stroke
				(width 0.1)
				(type default)
			)
			(layer "F.Fab")
		)
		(fp_line
			(start -0.12065 -0.305054)
			(end -0.12065 -0.2794)
			(stroke
				(width 0.1)
				(type default)
			)
			(layer "F.Fab")
		)
		(fp_line
			(start -0.67945 0.3048)
			(end -0.67945 -0.305054)
			(stroke
				(width 0.1)
				(type default)
			)
			(layer "F.Fab")
		)
		(fp_line
			(start -0.67945 -0.305054)
			(end -0.12065 -0.305054)
			(stroke
				(width 0.1)
				(type default)
			)
			(layer "F.Fab")
		)
		(pad "1" smd circle
			(at -0.40005 0 180)
			(size 0 0)
			(layers "F.Cu" "F.Mask" "F.Paste")
			(net "PWRGD_DSW_PWROK_R2")
		)
		(pad "2" smd circle
			(at 0.40005 0 180)
			(size 0 0)
			(layers "F.Cu" "F.Mask" "F.Paste")
			(net "PWRGD_DSW_PWROK")
		)
	)
	(footprint ""
		(layer "F.Cu")
		(at 196.329808 -402.766022 90)
		(property "Reference" "PC1525"
			(at 0 0 90)
			(layer "F.SilkS")
			(hide yes)
			(effects
				(font
					(size 1.27 1.27)
				)
			)
		)
		(property "Value" ""
			(at 0 0 90)
			(layer "F.Fab")
			(effects
				(font
					(size 1.27 1.27)
				)
			)
		)
		(duplicate_pad_numbers_are_jumpers no)
		(fp_line
			(start 0.7874 -0.4064)
			(end 0.7874 0.4064)
			(stroke
				(width 0.1524)
				(type default)
			)
			(layer "F.SilkS")
		)
		(fp_line
			(start -0.7874 -0.4064)
			(end 0.7874 -0.4064)
			(stroke
				(width 0.1524)
				(type default)
			)
			(layer "F.SilkS")
		)
		(fp_line
			(start 0.7874 0.4064)
			(end -0.7874 0.4064)
			(stroke
				(width 0.1524)
				(type default)
			)
			(layer "F.SilkS")
		)
		(fp_line
			(start -0.7874 0.4064)
			(end -0.7874 -0.4064)
			(stroke
				(width 0.1524)
				(type default)
			)
			(layer "F.SilkS")
		)
		(fp_line
			(start -0.12065 -0.305054)
			(end -0.12065 -0.2794)
			(stroke
				(width 0.1)
				(type default)
			)
			(layer "F.Fab")
		)
		(fp_line
			(start -0.67945 -0.305054)
			(end -0.12065 -0.305054)
			(stroke
				(width 0.1)
				(type default)
			)
			(layer "F.Fab")
		)
		(fp_line
			(start 0.67945 -0.3048)
			(end 0.67945 0.3048)
			(stroke
				(width 0.1)
				(type default)
			)
			(layer "F.Fab")
		)
		(fp_line
			(start 0.12065 -0.3048)
			(end 0.67945 -0.3048)
			(stroke
				(width 0.1)
				(type default)
			)
			(layer "F.Fab")
		)
		(fp_line
			(start 0.12065 -0.2794)
			(end 0.12065 -0.3048)
			(stroke
				(width 0.1)
				(type default)
			)
			(layer "F.Fab")
		)
		(fp_line
			(start -0.12065 -0.2794)
			(end 0.12065 -0.2794)
			(stroke
				(width 0.1)
				(type default)
			)
			(layer "F.Fab")
		)
		(fp_line
			(start 0.120396 0.2794)
			(end -0.12065 0.2794)
			(stroke
				(width 0.1)
				(type default)
			)
			(layer "F.Fab")
		)
		(fp_line
			(start -0.12065 0.2794)
			(end -0.12065 0.3048)
			(stroke
				(width 0.1)
				(type default)
			)
			(layer "F.Fab")
		)
		(fp_line
			(start 0.67945 0.3048)
			(end 0.120396 0.3048)
			(stroke
				(width 0.1)
				(type default)
			)
			(layer "F.Fab")
		)
		(fp_line
			(start 0.120396 0.3048)
			(end 0.120396 0.2794)
			(stroke
				(width 0.1)
				(type default)
			)
			(layer "F.Fab")
		)
		(fp_line
			(start -0.12065 0.3048)
			(end -0.67945 0.3048)
			(stroke
				(width 0.1)
				(type default)
			)
			(layer "F.Fab")
		)
		(fp_line
			(start -0.67945 0.3048)
			(end -0.67945 -0.305054)
			(stroke
				(width 0.1)
				(type default)
			)
			(layer "F.Fab")
		)
		(pad "1" smd circle
			(at -0.40005 0 90)
			(size 0 0)
			(layers "F.Cu" "F.Mask" "F.Paste")
			(net "HSC_VDD_R_1")
		)
		(pad "2" smd circle
			(at 0.40005 0 90)
			(size 0 0)
			(layers "F.Cu" "F.Mask" "F.Paste")
			(net "AGND_HSC")
		)
	)
	(footprint ""
		(layer "F.Cu")
		(at 438.87771 -44.976288 180)
		(property "Reference" "R3240"
			(at 0 0 180)
			(layer "F.SilkS")
			(hide yes)
			(effects
				(font
					(size 1.27 1.27)
				)
			)
		)
		(property "Value" ""
			(at 0 0 180)
			(layer "F.Fab")
			(effects
				(font
					(size 1.27 1.27)
				)
			)
		)
		(duplicate_pad_numbers_are_jumpers no)
		(fp_line
			(start 0.7874 0.4064)
			(end -0.7874 0.4064)
			(stroke
				(width 0.1524)
				(type default)
			)
			(layer "F.SilkS")
		)
		(fp_line
			(start 0.7874 -0.4064)
			(end 0.7874 0.4064)
			(stroke
				(width 0.1524)
				(type default)
			)
			(layer "F.SilkS")
		)
		(fp_line
			(start -0.7874 0.4064)
			(end -0.7874 -0.4064)
			(stroke
				(width 0.1524)
				(type default)
			)
			(layer "F.SilkS")
		)
		(fp_line
			(start -0.7874 -0.4064)
			(end 0.7874 -0.4064)
			(stroke
				(width 0.1524)
				(type default)
			)
			(layer "F.SilkS")
		)
		(fp_line
			(start 0.67945 0.3048)
			(end 0.120396 0.3048)
			(stroke
				(width 0.1)
				(type default)
			)
			(layer "F.Fab")
		)
		(fp_line
			(start 0.67945 -0.3048)
			(end 0.67945 0.3048)
			(stroke
				(width 0.1)
				(type default)
			)
			(layer "F.Fab")
		)
		(fp_line
			(start 0.12065 -0.2794)
			(end 0.12065 -0.3048)
			(stroke
				(width 0.1)
				(type default)
			)
			(layer "F.Fab")
		)
		(fp_line
			(start 0.12065 -0.3048)
			(end 0.67945 -0.3048)
			(stroke
				(width 0.1)
				(type default)
			)
			(layer "F.Fab")
		)
		(fp_line
			(start 0.120396 0.3048)
			(end 0.120396 0.2794)
			(stroke
				(width 0.1)
				(type default)
			)
			(layer "F.Fab")
		)
		(fp_line
			(start 0.120396 0.2794)
			(end -0.12065 0.2794)
			(stroke
				(width 0.1)
				(type default)
			)
			(layer "F.Fab")
		)
		(fp_line
			(start -0.12065 0.3048)
			(end -0.67945 0.3048)
			(stroke
				(width 0.1)
				(type default)
			)
			(layer "F.Fab")
		)
		(fp_line
			(start -0.12065 0.2794)
			(end -0.12065 0.3048)
			(stroke
				(width 0.1)
				(type default)
			)
			(layer "F.Fab")
		)
		(fp_line
			(start -0.12065 -0.2794)
			(end 0.12065 -0.2794)
			(stroke
				(width 0.1)
				(type default)
			)
			(layer "F.Fab")
		)
		(fp_line
			(start -0.12065 -0.305054)
			(end -0.12065 -0.2794)
			(stroke
				(width 0.1)
				(type default)
			)
			(layer "F.Fab")
		)
		(fp_line
			(start -0.67945 0.3048)
			(end -0.67945 -0.305054)
			(stroke
				(width 0.1)
				(type default)
			)
			(layer "F.Fab")
		)
		(fp_line
			(start -0.67945 -0.305054)
			(end -0.12065 -0.305054)
			(stroke
				(width 0.1)
				(type default)
			)
			(layer "F.Fab")
		)
		(pad "1" smd circle
			(at -0.40005 0 180)
			(size 0 0)
			(layers "F.Cu" "F.Mask" "F.Paste")
			(net "SMB_OCP_SFF_3V3AUX_SCL")
		)
		(pad "2" smd circle
			(at 0.40005 0 180)
			(size 0 0)
			(layers "F.Cu" "F.Mask" "F.Paste")
			(net "P3V3_AUX")
		)
	)
	(footprint ""
		(layer "F.Cu")
		(at 349.100648 -408.517344 -90)
		(property "Reference" "C931"
			(at 0 0 270)
			(layer "F.SilkS")
			(hide yes)
			(effects
				(font
					(size 1.27 1.27)
				)
			)
		)
		(property "Value" ""
			(at 0 0 270)
			(layer "F.Fab")
			(effects
				(font
					(size 1.27 1.27)
				)
			)
		)
		(duplicate_pad_numbers_are_jumpers no)
		(fp_line
			(start -0.299974 0.150114)
			(end -0.299974 -0.150114)
			(stroke
				(width 0.1)
				(type default)
			)
			(layer "F.Fab")
		)
		(fp_line
			(start 0.299974 0.150114)
			(end -0.299974 0.150114)
			(stroke
				(width 0.1)
				(type default)
			)
			(layer "F.Fab")
		)
		(fp_line
			(start -0.299974 -0.150114)
			(end 0.299974 -0.150114)
			(stroke
				(width 0.1)
				(type default)
			)
			(layer "F.Fab")
		)
		(fp_line
			(start 0.299974 -0.150114)
			(end 0.299974 0.150114)
			(stroke
				(width 0.1)
				(type default)
			)
			(layer "F.Fab")
		)
		(pad "1" smd rect
			(at -0.2667 0 270)
			(size 0.3048 0.381)
			(layers "F.Cu" "F.Mask" "F.Paste")
			(net "P5E_CPU0_PE0_TX_C_DP<1>")
		)
		(pad "2" smd rect
			(at 0.2667 0 270)
			(size 0.3048 0.381)
			(layers "F.Cu" "F.Mask" "F.Paste")
			(net "P5E_CPU0_PE0_TX_DP<1>")
		)
	)
	(footprint ""
		(layer "F.Cu")
		(at 203.7588 -92.6338 -90)
		(property "Reference" "C2381"
			(at 0 0 270)
			(layer "F.SilkS")
			(hide yes)
			(effects
				(font
					(size 1.27 1.27)
				)
			)
		)
		(property "Value" ""
			(at 0 0 270)
			(layer "F.Fab")
			(effects
				(font
					(size 1.27 1.27)
				)
			)
		)
		(duplicate_pad_numbers_are_jumpers no)
		(fp_line
			(start -0.7874 0.4064)
			(end -0.7874 -0.4064)
			(stroke
				(width 0.1524)
				(type default)
			)
			(layer "F.SilkS")
		)
		(fp_line
			(start 0.7874 0.4064)
			(end -0.7874 0.4064)
			(stroke
				(width 0.1524)
				(type default)
			)
			(layer "F.SilkS")
		)
		(fp_line
			(start -0.7874 -0.4064)
			(end 0.7874 -0.4064)
			(stroke
				(width 0.1524)
				(type default)
			)
			(layer "F.SilkS")
		)
		(fp_line
			(start 0.7874 -0.4064)
			(end 0.7874 0.4064)
			(stroke
				(width 0.1524)
				(type default)
			)
			(layer "F.SilkS")
		)
		(fp_line
			(start -0.67945 0.3048)
			(end -0.67945 -0.305054)
			(stroke
				(width 0.1)
				(type default)
			)
			(layer "F.Fab")
		)
		(fp_line
			(start -0.12065 0.3048)
			(end -0.67945 0.3048)
			(stroke
				(width 0.1)
				(type default)
			)
			(layer "F.Fab")
		)
		(fp_line
			(start 0.120396 0.3048)
			(end 0.120396 0.2794)
			(stroke
				(width 0.1)
				(type default)
			)
			(layer "F.Fab")
		)
		(fp_line
			(start 0.67945 0.3048)
			(end 0.120396 0.3048)
			(stroke
				(width 0.1)
				(type default)
			)
			(layer "F.Fab")
		)
		(fp_line
			(start -0.12065 0.2794)
			(end -0.12065 0.3048)
			(stroke
				(width 0.1)
				(type default)
			)
			(layer "F.Fab")
		)
		(fp_line
			(start 0.120396 0.2794)
			(end -0.12065 0.2794)
			(stroke
				(width 0.1)
				(type default)
			)
			(layer "F.Fab")
		)
		(fp_line
			(start -0.12065 -0.2794)
			(end 0.12065 -0.2794)
			(stroke
				(width 0.1)
				(type default)
			)
			(layer "F.Fab")
		)
		(fp_line
			(start 0.12065 -0.2794)
			(end 0.12065 -0.3048)
			(stroke
				(width 0.1)
				(type default)
			)
			(layer "F.Fab")
		)
		(fp_line
			(start 0.12065 -0.3048)
			(end 0.67945 -0.3048)
			(stroke
				(width 0.1)
				(type default)
			)
			(layer "F.Fab")
		)
		(fp_line
			(start 0.67945 -0.3048)
			(end 0.67945 0.3048)
			(stroke
				(width 0.1)
				(type default)
			)
			(layer "F.Fab")
		)
		(fp_line
			(start -0.67945 -0.305054)
			(end -0.12065 -0.305054)
			(stroke
				(width 0.1)
				(type default)
			)
			(layer "F.Fab")
		)
		(fp_line
			(start -0.12065 -0.305054)
			(end -0.12065 -0.2794)
			(stroke
				(width 0.1)
				(type default)
			)
			(layer "F.Fab")
		)
		(pad "1" smd circle
			(at -0.40005 0 270)
			(size 0 0)
			(layers "F.Cu" "F.Mask" "F.Paste")
			(net "P12V_AUX_UV_ADR_TRIGGER")
		)
		(pad "2" smd circle
			(at 0.40005 0 270)
			(size 0 0)
			(layers "F.Cu" "F.Mask" "F.Paste")
			(net "GND")
		)
	)
)
